#ISCELL
  mstr_misc dns *
  *
#ISCELL
  pure_quanta quanta_title_block_c *
  *
#ISCELL
  logical_power universal_gnd *
  page28_i100
#CELL
  pure_quanta q_cap *
  page28_i101
#ISCELL
  logical_power universal_gnd *
  page28_i102
#ISCELL
  standard offpage *
  page28_i103
#CELL
  pure_quanta q_res *
  page28_i104
#CELL
  pure_quanta q_res *
  page28_i105
#ISCELL
  logical_power universal_gnd *
  page28_i106
#ISCELL
  logical_power universal_power *
  page28_i107
#CELL
  pure_quanta q_res *
  page28_i108
#CELL
  pure_quanta q_res *
  page28_i109
#ISCELL
  logical_power vccaux15 *
  page28_i110
#CELL
  pure_quanta q_res *
  page28_i113
#ISCELL
  logical_power universal_gnd *
  page28_i115
#ISCELL
  standard offpage *
  page28_i116
#ISCELL
  standard offpage *
  page28_i117
#ISCELL
  standard offpage *
  page28_i118
#ISCELL
  standard offpage *
  page28_i121
#ISCELL
  standard offpage *
  page28_i122
#ISCELL
  standard offpage *
  page28_i123
#ISCELL
  standard offpage *
  page28_i124
#CELL
  pure_quanta q_res *
  page28_i125
#CELL
  pure_quanta q_res *
  page28_i126
#CELL
  pure_quanta q_res *
  page28_i127
#CELL
  pure_quanta q_res *
  page28_i128
#ISCELL
  standard offpage *
  page28_i129
#ISCELL
  standard offpage *
  page28_i130
#ISCELL
  standard offpage *
  page28_i131
#ISCELL
  standard offpage *
  page28_i132
#ISCELL
  standard offpage *
  page28_i133
#ISCELL
  standard offpage *
  page28_i134
#ISCELL
  standard offpage *
  page28_i135
#ISCELL
  standard offpage *
  page28_i136
#ISCELL
  standard offpage *
  page28_i137
#ISCELL
  standard offpage *
  page28_i138
#ISCELL
  standard offpage *
  page28_i139
#ISCELL
  logical_power universal_gnd *
  page28_i140
#CELL
  pure_quanta pca9555pw *
  page28_i141
#ISCELL
  standard offpage *
  page28_i142
#ISCELL
  standard offpage *
  page28_i143
#CELL
  pure_quanta q_res *
  page28_i144
#CELL
  pure_quanta q_res *
  page28_i145
#CELL
  pure_quanta q_cap *
  page28_i146
#CELL
  pure_quanta q_res *
  page28_i147
#ISCELL
  logical_power universal_gnd *
  page28_i148
#ISCELL
  standard offpage *
  page28_i149
#ISCELL
  standard offpage *
  page28_i150
#ISCELL
  standard offpage *
  page28_i151
#CELL
  pure_quanta q_res *
  page28_i152
#CELL
  pure_quanta q_res *
  page28_i153
#ISCELL
  logical_power universal_power *
  page28_i154
#ISCELL
  logical_power universal_power *
  page28_i155
#ISCELL
  standard offpage *
  page28_i156
#ISCELL
  standard offpage *
  page28_i157
#ISCELL
  standard offpage *
  page28_i158
#ISCELL
  logical_power universal_gnd *
  page28_i159
#ISCELL
  logical_power universal_power *
  page28_i160
#CELL
  pure_quanta q_res *
  page28_i161
#CELL
  pure_quanta q_res *
  page28_i162
#CELL
  pure_quanta 2n7002a7 *
  page28_i163
#CELL
  pure_quanta q_res *
  page28_i164
#ISCELL
  logical_power universal_power *
  page28_i165
#CELL
  pure_quanta q_res *
  page28_i166
#ISCELL
  standard offpage *
  page28_i167
#CELL
  pure_quanta q_res *
  page28_i168
#CELL
  pure_quanta q_res *
  page28_i169
#ISCELL
  logical_power universal_power *
  page28_i170
#CELL
  pure_quanta q_res *
  page28_i171
#CELL
  pure_quanta q_res *
  page28_i172
#CELL
  pure_quanta q_res *
  page28_i173
#ISCELL
  logical_power universal_gnd *
  page28_i174
#CELL
  pure_quanta q_res *
  page28_i175
#ISCELL
  standard offpage *
  page28_i176
#ISCELL
  standard offpage *
  page28_i177
#ISCELL
  standard offpage *
  page28_i178
#CELL
  pure_quanta ncp380hsnajaat1g *
  page28_i179
#CELL
  pure_quanta 74lvc1g07w57 *
  page28_i180
#CELL
  pure_quanta q_cap *
  page28_i181
#ISCELL
  logical_power universal_gnd *
  page28_i182
#CELL
  pure_quanta q_res *
  page28_i183
#CELL
  pure_quanta q_res *
  page28_i184
#CELL
  pure_quanta q_res *
  page28_i185
#CELL
  pure_quanta q_cap *
  page28_i35
#ISCELL
  logical_power universal_gnd *
  page28_i36
#ISCELL
  logical_power universal_power *
  page28_i37
#CELL
  pure_quanta q_cap *
  page28_i38
#ISCELL
  standard offpage *
  page28_i39
#ISCELL
  logical_power universal_power *
  page28_i40
#CELL
  pure_quanta q_res *
  page28_i42
#ISCELL
  logical_power universal_power *
  page28_i50
#ISCELL
  logical_power universal_power *
  page28_i52
#ISCELL
  logical_power universal_gnd *
  page28_i53
#CELL
  pure_quanta q_res *
  page28_i54
#ISCELL
  logical_power universal_power *
  page28_i61
#CELL
  pure_quanta q_res *
  page28_i62
#CELL
  pure_quanta q_res *
  page28_i63
#ISCELL
  logical_power universal_gnd *
  page28_i64
#ISCELL
  logical_power vccaux15 *
  page28_i87
#ISCELL
  logical_power vccaux15 *
  page28_i88
#ISCELL
  standard offpage *
  page28_i89
#ISCELL
  standard offpage *
  page28_i90
#CELL
  pure_quanta q_res *
  page28_i91
#ISCELL
  standard offpage *
  page28_i94
#ISCELL
  logical_power vccaux15 *
  page28_i95
#CELL
  pure_quanta q_res *
  page28_i96
#ISCELL
  logical_power universal_gnd *
  page28_i97
#CELL
  pure_quanta q_cap *
  page28_i98
#CELL
  pure_quanta pca9517adp *
  page28_i99
